(kicad_pcb
	(version 20241229)
	(generator "pcbnew")
	(generator_version "9.0")
	(general
		(thickness 1.711)
		(legacy_teardrops no)
	)
	(paper "A4")
	(title_block
		(title "Antmicro Baseboard for Jetson AGX Thor")
		(date "2026-02-18")
		(rev "1.1.0")
		(company "Antmicro Ltd")
		(comment 1 "www.antmicro.com")
		(comment 9 "footprints 606-609 of 1170")
	)
	(layers
		(0 "F.Cu" signal)
		(4 "In1.Cu" signal)
		(6 "In2.Cu" signal)
		(8 "In3.Cu" signal)
		(10 "In4.Cu" jumper)
		(12 "In5.Cu" signal)
		(14 "In6.Cu" signal)
		(16 "In7.Cu" signal)
		(18 "In8.Cu" signal)
		(2 "B.Cu" signal)
		(9 "F.Adhes" user "F.Adhesive")
		(11 "B.Adhes" user "B.Adhesive")
		(13 "F.Paste" user)
		(15 "B.Paste" user)
		(5 "F.SilkS" user "F.Silkscreen")
		(7 "B.SilkS" user "B.Silkscreen")
		(1 "F.Mask" user)
		(3 "B.Mask" user)
		(17 "Dwgs.User" user "User.Drawings")
		(19 "Cmts.User" user "User.Comments")
		(21 "Eco1.User" user "User.Eco1")
		(23 "Eco2.User" user "User.Eco2")
		(25 "Edge.Cuts" user)
		(27 "Margin" user)
		(31 "F.CrtYd" user "F.Courtyard")
		(29 "B.CrtYd" user "B.Courtyard")
		(35 "F.Fab" user)
		(33 "B.Fab" user)
	)
	(footprint "antmicro-footprints:C_0402_1005Metric"
		(layer "F.Cu")
		(at 91.1 92.7)
		(descr "Capacitor SMD 0402")
		(tags "capacitor SMD 0402")
		(property "Reference" "C351"
			(at 1.1 0.5 0)
			(layer "F.SilkS")
			(effects
				(font
					(size 0.7 0.7)
					(thickness 0.15)
				)
				(justify left bottom)
			)
		)
		(property "Value" "C_100n_0402"
			(at -1.022927 2.155213 0)
			(layer "F.Fab")
			(effects
				(font
					(size 0.7 0.7)
					(thickness 0.15)
				)
				(justify left bottom)
			)
		)
		(property "Datasheet" "https://www.murata.com/products/productdetail?partno=GRM155R61H104KE14%23"
			(at 0 0 0)
			(layer "F.Fab")
			(hide yes)
			(effects
				(font
					(size 1.27 1.27)
					(thickness 0.15)
				)
			)
		)
		(property "Description" "SMD Multilayer Ceramic Capacitor, 0.1 µF, 50 V, 0402 [1005 Metric], ± 10%, X5R, GRM Series"
			(at 0 0 0)
			(layer "F.Fab")
			(hide yes)
			(effects
				(font
					(size 1.27 1.27)
					(thickness 0.15)
				)
			)
		)
		(property "Manufacturer" "Murata"
			(at 0 0 0)
			(unlocked yes)
			(layer "F.Fab")
			(hide yes)
			(effects
				(font
					(size 1 1)
					(thickness 0.15)
				)
			)
		)
		(property "MPN" "GRM155R61H104KE14D"
			(at 0 0 0)
			(unlocked yes)
			(layer "F.Fab")
			(hide yes)
			(effects
				(font
					(size 1 1)
					(thickness 0.15)
				)
			)
		)
		(property "Val" "100n"
			(at 0 0 0)
			(unlocked yes)
			(layer "F.Fab")
			(hide yes)
			(effects
				(font
					(size 1 1)
					(thickness 0.15)
				)
			)
		)
		(property "License" "Apache-2.0"
			(at 0 0 0)
			(unlocked yes)
			(layer "F.Fab")
			(hide yes)
			(effects
				(font
					(size 1 1)
					(thickness 0.15)
				)
			)
		)
		(property "Author" "Antmicro"
			(at 0 0 0)
			(unlocked yes)
			(layer "F.Fab")
			(hide yes)
			(effects
				(font
					(size 1 1)
					(thickness 0.15)
				)
			)
		)
		(property "Voltage" "50V"
			(at 0 0 0)
			(unlocked yes)
			(layer "F.Fab")
			(hide yes)
			(effects
				(font
					(size 1 1)
					(thickness 0.15)
				)
			)
		)
		(property "Dielectric" "X5R"
			(at 0 0 0)
			(unlocked yes)
			(layer "F.Fab")
			(hide yes)
			(effects
				(font
					(size 1 1)
					(thickness 0.15)
				)
			)
		)
		(sheetname "/SoM_IO2/")
		(sheetfile "som_io2.kicad_sch")
		(attr smd)
		(fp_poly
			(pts
				(xy -0.925 -0.47) (xy 0.925 -0.47) (xy 0.925 0.47) (xy -0.925 0.47)
			)
			(stroke
				(width 0.05)
				(type default)
			)
			(fill no)
			(layer "F.CrtYd")
		)
		(fp_line
			(start -0.494 -0.25)
			(end 0.504 -0.25)
			(stroke
				(width 0.15)
				(type solid)
			)
			(layer "F.Fab")
		)
		(fp_line
			(start -0.494 0.248)
			(end -0.494 -0.25)
			(stroke
				(width 0.15)
				(type solid)
			)
			(layer "F.Fab")
		)
		(fp_line
			(start 0.504 -0.25)
			(end 0.504 0.248)
			(stroke
				(width 0.15)
				(type solid)
			)
			(layer "F.Fab")
		)
		(fp_line
			(start 0.504 0.248)
			(end -0.494 0.248)
			(stroke
				(width 0.15)
				(type solid)
			)
			(layer "F.Fab")
		)
		(fp_text user "License: Apache-2.0"
			(at -0.939 5.799 0)
			(layer "F.Fab")
			(effects
				(font
					(size 0.7 0.7)
					(thickness 0.15)
				)
				(justify left bottom)
			)
		)
		(fp_text user "${REFERENCE}"
			(at -0.939 4.599 0)
			(layer "F.Fab")
			(effects
				(font
					(size 0.7 0.7)
					(thickness 0.15)
				)
				(justify left bottom)
			)
		)
		(fp_text user "Author: Antmicro"
			(at -0.939 3.399 0)
			(layer "F.Fab")
			(effects
				(font
					(size 0.7 0.7)
					(thickness 0.15)
				)
				(justify left bottom)
			)
		)
		(pad "1" smd roundrect
			(at -0.48 0)
			(size 0.59 0.64)
			(layers "F.Cu" "F.Mask" "F.Paste")
			(roundrect_rratio 0.25)
			(net 661 "/Expansion connector/DP3.TX3-")
			(pintype "passive")
		)
		(pad "2" smd roundrect
			(at 0.48 0)
			(size 0.59 0.64)
			(layers "F.Cu" "F.Mask" "F.Paste")
			(roundrect_rratio 0.25)
			(net 1271 "/SoM_IO2/DP3.TX3_C-")
			(pintype "passive")
		)
	)
	(footprint "antmicro-footprints:SOT-563"
		(layer "F.Cu")
		(at 145.604391 128.21 90)
		(property "Reference" "U7"
			(at 4.01 0.895609 0)
			(layer "F.SilkS")
			(effects
				(font
					(size 0.7 0.7)
					(thickness 0.15)
				)
				(justify right top)
			)
		)
		(property "Value" "TPS564247DRLR"
			(at 0 2 90)
			(layer "F.Fab")
			(effects
				(font
					(size 0.7 0.7)
					(thickness 0.15)
				)
				(justify left bottom)
			)
		)
		(property "Datasheet" "https://www.ti.com/lit/ds/symlink/tps564247.pdf?ts=1713526387938&ref_url=https%253A%252F%252Fwww.mouser.pl%252F"
			(at 0 0 90)
			(layer "F.Fab")
			(hide yes)
			(effects
				(font
					(size 1.27 1.27)
					(thickness 0.15)
				)
			)
		)
		(property "Description" "Switching Voltage Regulators 3-V to 16-V input voltage, 4-A FCCM mode, synchronous buck converter in SOT-563 package 6-SOT-5X3 -40 to 125"
			(at 0 0 90)
			(layer "F.Fab")
			(hide yes)
			(effects
				(font
					(size 1.27 1.27)
					(thickness 0.15)
				)
			)
		)
		(property "MPN" "TPS564247DRLR"
			(at 0 0 90)
			(unlocked yes)
			(layer "F.Fab")
			(hide yes)
			(effects
				(font
					(size 1 1)
					(thickness 0.15)
				)
			)
		)
		(property "Author" "Antmicro"
			(at 0 0 90)
			(unlocked yes)
			(layer "F.Fab")
			(hide yes)
			(effects
				(font
					(size 1 1)
					(thickness 0.15)
				)
			)
		)
		(property "License" "Apache-2.0"
			(at 0 0 90)
			(unlocked yes)
			(layer "F.Fab")
			(hide yes)
			(effects
				(font
					(size 1 1)
					(thickness 0.15)
				)
			)
		)
		(property "Manufacturer" "Texas Instruments"
			(at 0 0 90)
			(unlocked yes)
			(layer "F.Fab")
			(hide yes)
			(effects
				(font
					(size 1 1)
					(thickness 0.15)
				)
			)
		)
		(component_classes
			(class "DCDC_1V8")
		)
		(sheetname "/DCDC/")
		(sheetfile "dcdc.kicad_sch")
		(attr smd)
		(fp_line
			(start 0.776 -0.974)
			(end 0.526 -0.974)
			(stroke
				(width 0.15)
				(type solid)
			)
			(layer "F.SilkS")
		)
		(fp_line
			(start 0.776 -0.974)
			(end 0.776 -0.778)
			(stroke
				(width 0.15)
				(type solid)
			)
			(layer "F.SilkS")
		)
		(fp_line
			(start -0.499 -0.974)
			(end -0.724 -0.778)
			(stroke
				(width 0.15)
				(type solid)
			)
			(layer "F.SilkS")
		)
		(fp_line
			(start 0.776 0.776)
			(end 0.776 0.972)
			(stroke
				(width 0.15)
				(type solid)
			)
			(layer "F.SilkS")
		)
		(fp_line
			(start -0.778 0.776)
			(end -0.778 0.949)
			(stroke
				(width 0.15)
				(type solid)
			)
			(layer "F.SilkS")
		)
		(fp_line
			(start -0.778 0.949)
			(end -0.424 0.949)
			(stroke
				(width 0.15)
				(type solid)
			)
			(layer "F.SilkS")
		)
		(fp_line
			(start 0.776 0.972)
			(end 0.526 0.972)
			(stroke
				(width 0.15)
				(type solid)
			)
			(layer "F.SilkS")
		)
		(fp_circle
			(center -0.903 -0.999)
			(end -0.952 -0.95)
			(stroke
				(width 0.15)
				(type solid)
			)
			(fill yes)
			(layer "F.SilkS")
		)
		(fp_rect
			(start 1.19 -1.12)
			(end -1.2 1.1)
			(stroke
				(width 0.05)
				(type solid)
			)
			(fill no)
			(layer "F.CrtYd")
		)
		(fp_line
			(start 0.651 -0.849)
			(end 0.651 0.847)
			(stroke
				(width 0.15)
				(type solid)
			)
			(layer "F.Fab")
		)
		(fp_line
			(start -0.453 -0.849)
			(end 0.651 -0.849)
			(stroke
				(width 0.15)
				(type solid)
			)
			(layer "F.Fab")
		)
		(fp_line
			(start -0.453 -0.849)
			(end -0.653 -0.678)
			(stroke
				(width 0.15)
				(type solid)
			)
			(layer "F.Fab")
		)
		(fp_line
			(start -0.653 -0.678)
			(end -0.653 0.847)
			(stroke
				(width 0.15)
				(type solid)
			)
			(layer "F.Fab")
		)
		(fp_line
			(start 0.651 0.847)
			(end -0.653 0.847)
			(stroke
				(width 0.15)
				(type solid)
			)
			(layer "F.Fab")
		)
		(fp_text user "${REFERENCE}"
			(at -1.299 7.323 90)
			(layer "F.Fab")
			(effects
				(font
					(size 0.7 0.7)
					(thickness 0.15)
				)
				(justify left bottom)
			)
		)
		(fp_text user "License: Apache-2.0"
			(at -1.299 4.924 90)
			(layer "F.Fab")
			(effects
				(font
					(size 0.7 0.7)
					(thickness 0.15)
				)
				(justify left bottom)
			)
		)
		(fp_text user "Author: Antmicro"
			(at -1.299 6.124 90)
			(layer "F.Fab")
			(effects
				(font
					(size 0.7 0.7)
					(thickness 0.15)
				)
				(justify left bottom)
			)
		)
		(pad "1" smd roundrect
			(at -0.749 -0.499)
			(size 0.3 0.6)
			(layers "F.Cu" "F.Mask" "F.Paste")
			(roundrect_rratio 0.25)
			(net 5 "+5V")
			(pinfunction "V_{IN}")
			(pintype "power_in")
		)
		(pad "2" smd roundrect
			(at -0.749 0.001)
			(size 0.3 0.6)
			(layers "F.Cu" "F.Mask" "F.Paste")
			(roundrect_rratio 0.25)
			(net 1185 "/DCDC/1V8_SW")
			(pinfunction "SW")
			(pintype "passive")
		)
		(pad "3" smd roundrect
			(at -0.749 0.497)
			(size 0.3 0.6)
			(layers "F.Cu" "F.Mask" "F.Paste")
			(roundrect_rratio 0.25)
			(net 1 "GND")
			(pinfunction "GND")
			(pintype "power_in")
		)
		(pad "4" smd roundrect
			(at 0.747 0.497)
			(size 0.3 0.6)
			(layers "F.Cu" "F.Mask" "F.Paste")
			(roundrect_rratio 0.25)
			(net 1 "GND")
			(pinfunction "AGND")
			(pintype "power_in")
		)
		(pad "5" smd roundrect
			(at 0.747 0.001)
			(size 0.3 0.6)
			(layers "F.Cu" "F.Mask" "F.Paste")
			(roundrect_rratio 0.25)
			(net 1293 "/DCDC/CARRIER_PWR_ON")
			(pinfunction "EN")
			(pintype "passive")
		)
		(pad "6" smd roundrect
			(at 0.747 -0.499)
			(size 0.3 0.6)
			(layers "F.Cu" "F.Mask" "F.Paste")
			(roundrect_rratio 0.25)
			(net 1222 "/DCDC/1V8_FB")
			(pinfunction "FB")
			(pintype "passive")
		)
	)
	(footprint "antmicro-footprints:TP_SMD_0.75mm"
		(layer "F.Cu")
		(at 69.279 60.671 90)
		(property "Reference" "TP23"
			(at 0.45 3.17 0)
			(layer "F.SilkS")
			(effects
				(font
					(size 0.7 0.7)
					(thickness 0.15)
				)
				(justify right top)
			)
		)
		(property "Value" "TP_0.75mm_SMD"
			(at 0 1.2 90)
			(layer "F.Fab")
			(effects
				(font
					(size 0.7 0.7)
					(thickness 0.15)
				)
				(justify left bottom)
			)
		)
		(property "Description" "SMT test point"
			(at 0 0 90)
			(layer "F.Fab")
			(hide yes)
			(effects
				(font
					(size 1.27 1.27)
					(thickness 0.15)
				)
			)
		)
		(property "MPN" ""
			(at 0 0 90)
			(unlocked yes)
			(layer "F.Fab")
			(hide yes)
			(effects
				(font
					(size 1 1)
					(thickness 0.15)
				)
			)
		)
		(property "Manufacturer" ""
			(at 0 0 90)
			(unlocked yes)
			(layer "F.Fab")
			(hide yes)
			(effects
				(font
					(size 1 1)
					(thickness 0.15)
				)
			)
		)
		(property "Author" "Antmicro"
			(at 0 0 90)
			(unlocked yes)
			(layer "F.Fab")
			(hide yes)
			(effects
				(font
					(size 1 1)
					(thickness 0.15)
				)
			)
		)
		(property "License" "Apache-2.0"
			(at 0 0 90)
			(unlocked yes)
			(layer "F.Fab")
			(hide yes)
			(effects
				(font
					(size 1 1)
					(thickness 0.15)
				)
			)
		)
		(sheetname "/CSI/")
		(sheetfile "csi.kicad_sch")
		(attr exclude_from_pos_files exclude_from_bom)
		(fp_circle
			(center 0 0)
			(end 0.475 0)
			(stroke
				(width 0.05)
				(type default)
			)
			(fill no)
			(layer "F.CrtYd")
		)
		(fp_text user "License: Apache-2.0"
			(at -0.4 5.101 90)
			(layer "F.Fab")
			(effects
				(font
					(size 0.7 0.7)
					(thickness 0.15)
				)
				(justify left bottom)
			)
		)
		(fp_text user "Author: Antmicro"
			(at -0.4 3.901 90)
			(layer "F.Fab")
			(effects
				(font
					(size 0.7 0.7)
					(thickness 0.15)
				)
				(justify left bottom)
			)
		)
		(fp_text user "${REFERENCE}"
			(at -0.4 2.7 90)
			(layer "F.Fab")
			(effects
				(font
					(size 0.7 0.7)
					(thickness 0.15)
				)
				(justify left bottom)
			)
		)
		(pad "1" smd circle
			(at 0 0 90)
			(size 0.75 0.75)
			(layers "F.Cu" "F.Mask")
			(net 1047 "/CSI/MUX_I2C_5_SDA")
			(pinfunction "1")
			(pintype "passive")
		)
	)
	(footprint "antmicro-footprints:SOT-523"
		(layer "F.Cu")
		(at 140.89 133.46 -90)
		(property "Reference" "Q11"
			(at -1.16 5.69 90)
			(layer "F.SilkS")
			(effects
				(font
					(size 0.7 0.7)
					(thickness 0.15)
				)
				(justify right top)
			)
		)
		(property "Value" "DMG1012T-7"
			(at 0.1 1.824 90)
			(layer "F.Fab")
			(effects
				(font
					(size 0.7 0.7)
					(thickness 0.15)
				)
				(justify right top)
			)
		)
		(property "Datasheet" "https://www.diodes.com/assets/Datasheets/ds31783.pdf"
			(at 0 0 90)
			(layer "F.Fab")
			(hide yes)
			(effects
				(font
					(size 1.27 1.27)
					(thickness 0.15)
				)
			)
		)
		(property "Description" "Power MOSFET, N Channel, 20 V, 630 mA, 0.3 ohm, SOT-523, Surface Mount"
			(at 0 0 90)
			(layer "F.Fab")
			(hide yes)
			(effects
				(font
					(size 1.27 1.27)
					(thickness 0.15)
				)
			)
		)
		(property "MPN" "DMG1012T-7"
			(at 0 0 90)
			(unlocked yes)
			(layer "F.Fab")
			(hide yes)
			(effects
				(font
					(size 1 1)
					(thickness 0.15)
				)
			)
		)
		(property "Manufacturer" "Diodes Incorporated"
			(at 0 0 90)
			(unlocked yes)
			(layer "F.Fab")
			(hide yes)
			(effects
				(font
					(size 1 1)
					(thickness 0.15)
				)
			)
		)
		(property "Author" "Antmicro"
			(at 0 0 90)
			(unlocked yes)
			(layer "F.Fab")
			(hide yes)
			(effects
				(font
					(size 1 1)
					(thickness 0.15)
				)
			)
		)
		(property "License" "Apache-2.0"
			(at 0 0 90)
			(unlocked yes)
			(layer "F.Fab")
			(hide yes)
			(effects
				(font
					(size 1 1)
					(thickness 0.15)
				)
			)
		)
		(sheetname "/SoM_Power/")
		(sheetfile "som_power.kicad_sch")
		(attr smd)
		(fp_line
			(start -0.927 -0.051)
			(end -0.927 -0.351)
			(stroke
				(width 0.15)
				(type solid)
			)
			(layer "F.SilkS")
		)
		(fp_line
			(start -0.927 -0.351)
			(end -0.725 -0.551)
			(stroke
				(width 0.15)
				(type solid)
			)
			(layer "F.SilkS")
		)
		(fp_line
			(start -0.725 -0.551)
			(end -0.277 -0.551)
			(stroke
				(width 0.15)
				(type solid)
			)
			(layer "F.SilkS")
		)
		(fp_line
			(start -0.277 -0.551)
			(end -0.277 -0.75)
			(stroke
				(width 0.15)
				(type solid)
			)
			(layer "F.SilkS")
		)
		(fp_circle
			(center -0.9652 0.9652)
			(end -0.9152 0.9652)
			(stroke
				(width 0.15)
				(type solid)
			)
			(fill yes)
			(layer "F.SilkS")
		)
		(fp_line
			(start -1.12 1.15)
			(end 1.1 1.15)
			(stroke
				(width 0.05)
				(type solid)
			)
			(layer "F.CrtYd")
		)
		(fp_line
			(start -1.12 -1.16)
			(end -1.12 1.15)
			(stroke
				(width 0.05)
				(type solid)
			)
			(layer "F.CrtYd")
		)
		(fp_line
			(start -1.12 -1.16)
			(end 1.1 -1.16)
			(stroke
				(width 0.05)
				(type solid)
			)
			(layer "F.CrtYd")
		)
		(fp_line
			(start 1.1 -1.16)
			(end 1.1 1.15)
			(stroke
				(width 0.05)
				(type solid)
			)
			(layer "F.CrtYd")
		)
		(fp_line
			(start 0.8 0.424)
			(end -0.802 0.424)
			(stroke
				(width 0.15)
				(type solid)
			)
			(layer "F.Fab")
		)
		(fp_line
			(start -0.802 -0.276)
			(end -0.802 0.424)
			(stroke
				(width 0.15)
				(type solid)
			)
			(layer "F.Fab")
		)
		(fp_line
			(start -0.652 -0.425)
			(end -0.802 -0.276)
			(stroke
				(width 0.15)
				(type solid)
			)
			(layer "F.Fab")
		)
		(fp_line
			(start 0.8 -0.425)
			(end 0.8 0.424)
			(stroke
				(width 0.15)
				(type solid)
			)
			(layer "F.Fab")
		)
		(fp_line
			(start 0.8 -0.425)
			(end -0.652 -0.425)
			(stroke
				(width 0.15)
				(type solid)
			)
			(layer "F.Fab")
		)
		(fp_circle
			(center -0.9652 0.9652)
			(end -0.9144 0.9652)
			(stroke
				(width 0.15)
				(type solid)
			)
			(fill no)
			(layer "F.Fab")
		)
		(fp_text user "${REFERENCE}"
			(at -1.12 3.824 90)
			(layer "F.Fab")
			(effects
				(font
					(size 0.7 0.7)
					(thickness 0.15)
				)
				(justify right top)
			)
		)
		(fp_text user "Author: Antmicro"
			(at -1.12 6.224 90)
			(layer "F.Fab")
			(effects
				(font
					(size 0.7 0.7)
					(thickness 0.15)
				)
				(justify right top)
			)
		)
		(fp_text user "License: Apache-2.0"
			(at -1.12 5.024 90)
			(layer "F.Fab")
			(effects
				(font
					(size 0.7 0.7)
					(thickness 0.15)
				)
				(justify right top)
			)
		)
		(pad "1" smd rect
			(at -0.5 0.65 270)
			(size 0.4 0.51)
			(layers "F.Cu" "F.Mask" "F.Paste")
			(net 883 "Net-(Q10-G)")
			(pinfunction "G")
			(pintype "input")
		)
		(pad "2" smd rect
			(at 0.498 0.65 270)
			(size 0.4 0.51)
			(layers "F.Cu" "F.Mask" "F.Paste")
			(net 1 "GND")
			(pinfunction "S")
			(pintype "passive")
		)
		(pad "3" smd rect
			(at 0 -0.652 270)
			(size 0.4 0.51)
			(layers "F.Cu" "F.Mask" "F.Paste")
			(net 886 "Net-(Q11-D)")
			(pinfunction "D")
			(pintype "passive")
		)
	)
)
